(kicad_pcb
	(version 20260206)
	(generator "pcbnew")
	(generator_version "10.0")
	(general
		(thickness 1.6)
		(legacy_teardrops no)
	)
	(paper "A4")
	(title_block
		(title "v1-chassis-manager — T6M_CM_d_v01_1031_1645.brd")
		(comment 1 "Open CloudServer (Microsoft) / footprint 1507 of 2512 (U2), pads 599-714 of 1283")
	)
	(layers
		(0 "F.Cu" signal "TOP")
		(4 "In1.Cu" signal "GND1")
		(6 "In2.Cu" signal "IN1")
		(8 "In3.Cu" signal "VCC1")
		(10 "In4.Cu" signal "VCC2")
		(12 "In5.Cu" signal "GND2")
		(14 "In6.Cu" signal "IN2")
		(16 "In7.Cu" signal "IN3")
		(18 "In8.Cu" signal "GND3")
		(2 "B.Cu" signal "BOTTOM")
		(9 "F.Adhes" user "F.Adhesive")
		(11 "B.Adhes" user "B.Adhesive")
		(13 "F.Paste" user "Package Geometry/Pastemask Top")
		(15 "B.Paste" user "Package Geometry/Pastemask Bottom")
		(5 "F.SilkS" user "Ref Des/Silkscreen Top")
		(7 "B.SilkS" user "Ref Des/Silkscreen Bottom")
		(1 "F.Mask" user "Board Geometry/Soldermask Top")
		(3 "B.Mask" user "Board Geometry/Soldermask Bottom")
		(17 "Dwgs.User" user "User.Drawings")
		(19 "Cmts.User" user "User.Comments")
		(21 "Eco1.User" user "User.Eco1")
		(23 "Eco2.User" user "User.Eco2")
		(25 "Edge.Cuts" user "Board Geometry/Outline")
		(27 "Margin" user)
		(31 "F.CrtYd" user "Package Geometry/Place Bound Top")
		(29 "B.CrtYd" user "Package Geometry/Place Bound Bottom")
		(35 "F.Fab" user "Ref Des/Assembly Top")
		(33 "B.Fab" user "Ref Des/Assembly Bottom")
	)
	(footprint ""
		(layer "F.Cu")
		(at 58.000646 -75.799442)
		(property "Reference" "U2"
			(at -20.2438 -18.364708 0)
			(unlocked yes)
			(layer "F.SilkS")
			(effects
				(font
					(size 1.6002 1.1938)
					(thickness 0.1524)
				)
				(justify left)
			)
		)
		(property "Value" ""
			(at 0 0 0)
			(layer "F.Fab")
			(effects
				(font
					(size 1.27 1.27)
				)
			)
		)
		(duplicate_pad_numbers_are_jumpers no)
		(pad "BD26" smd circle
			(at -3.50266 8.058404)
			(size 0.3048 0.3048)
			(layers "F.Cu" "F.Mask" "F.Paste")
			(net "M_DDR3_NODE1_DQS2N")
		)
		(pad "BD29" smd circle
			(at -2.216404 8.439404)
			(size 0.3048 0.3048)
			(layers "F.Cu" "F.Mask" "F.Paste")
			(net "GND")
		)
		(pad "BD30" smd circle
			(at -1.51638 8.439404)
			(size 0.3048 0.3048)
			(layers "F.Cu" "F.Mask" "F.Paste")
			(net "GND")
		)
		(pad "BD32" smd circle
			(at -0.230124 8.058404)
			(size 0.3048 0.3048)
			(layers "F.Cu" "F.Mask" "F.Paste")
			(net "GND")
		)
		(pad "BD34" smd circle
			(at 0.4699 8.058404)
			(size 0.3048 0.3048)
			(layers "F.Cu" "F.Mask" "F.Paste")
			(net "GND")
		)
		(pad "BD37" smd circle
			(at 1.756156 8.439404)
			(size 0.3048 0.3048)
			(layers "F.Cu" "F.Mask" "F.Paste")
			(net "PV_VDDR_NODE1")
		)
		(pad "BD38" smd circle
			(at 2.45618 8.439404)
			(size 0.3048 0.3048)
			(layers "F.Cu" "F.Mask" "F.Paste")
			(net "PV_VDDR_NODE1")
		)
		(pad "BD41" smd circle
			(at 3.742436 8.058404)
			(size 0.3048 0.3048)
			(layers "F.Cu" "F.Mask" "F.Paste")
			(net "M_DDR3_NODE1_CK0P")
		)
		(pad "BD42" smd circle
			(at 4.44246 8.058404)
			(size 0.3048 0.3048)
			(layers "F.Cu" "F.Mask" "F.Paste")
			(net "M_DDR3_NODE1_CK0N")
		)
		(pad "BD45" smd circle
			(at 5.728716 8.439404)
			(size 0.3048 0.3048)
			(layers "F.Cu" "F.Mask" "F.Paste")
			(net "PV_VDDR_NODE1")
		)
		(pad "BD46" smd circle
			(at 6.42874 8.439404)
			(size 0.3048 0.3048)
			(layers "F.Cu" "F.Mask" "F.Paste")
			(net "GND")
		)
		(pad "BD49" smd circle
			(at 7.714996 8.058404)
			(size 0.3048 0.3048)
			(layers "F.Cu" "F.Mask" "F.Paste")
			(net "M_DDR3_NODE1_ECC4")
		)
		(pad "BD50" smd circle
			(at 8.41502 8.058404)
			(size 0.3048 0.3048)
			(layers "F.Cu" "F.Mask" "F.Paste")
			(net "M_DDR3_NODE1_ECC3")
		)
		(pad "BD53" smd circle
			(at 9.701276 8.439404)
			(size 0.3048 0.3048)
			(layers "F.Cu" "F.Mask" "F.Paste")
			(net "GND")
		)
		(pad "BD54" smd circle
			(at 10.4013 8.439404)
			(size 0.3048 0.3048)
			(layers "F.Cu" "F.Mask" "F.Paste")
			(net "GND")
		)
		(pad "BD59" smd circle
			(at 12.582398 8.175244)
			(size 0.3048 0.3048)
			(layers "F.Cu" "F.Mask" "F.Paste")
			(net "GND")
		)
		(pad "BD60" smd circle
			(at 13.344398 8.175244)
			(size 0.3048 0.3048)
			(layers "F.Cu" "F.Mask" "F.Paste")
			(net "M1_DQ_NODE1_DQ43")
		)
		(pad "BD62" smd circle
			(at 14.063218 8.391398)
			(size 0.3048 0.3048)
			(layers "F.Cu" "F.Mask" "F.Paste")
			(net "GND")
		)
		(pad "BD63" smd circle
			(at 14.751558 8.222488)
			(size 0.3048 0.3048)
			(layers "F.Cu" "F.Mask" "F.Paste")
			(net "M1_DQ_NODE1_DQ54")
		)
		(pad "BD65" smd circle
			(at 15.805658 8.142732)
			(size 0.3048 0.3048)
			(layers "F.Cu" "F.Mask" "F.Paste")
			(net "M1_DQ_NODE1_DQ48")
		)
		(pad "BE5" smd circle
			(at -14.063218 8.598662)
			(size 0.3048 0.3048)
			(layers "F.Cu" "F.Mask" "F.Paste")
			(net "CLK_100M_PCIE_RP0_NODE1_DP")
		)
		(pad "BE17" smd circle
			(at -8.175244 8.820404)
			(size 0.3048 0.3048)
			(layers "F.Cu" "F.Mask" "F.Paste")
			(net "GND")
		)
		(pad "BE19" smd circle
			(at -7.47522 8.820404)
			(size 0.3048 0.3048)
			(layers "F.Cu" "F.Mask" "F.Paste")
			(net "GND")
		)
		(pad "BE25" smd circle
			(at -4.202684 8.820404)
			(size 0.3048 0.3048)
			(layers "F.Cu" "F.Mask" "F.Paste")
			(net "GND")
		)
		(pad "BE26" smd circle
			(at -3.50266 8.820404)
			(size 0.3048 0.3048)
			(layers "F.Cu" "F.Mask" "F.Paste")
			(net "M_DDR3_NODE1_DQS2P")
		)
		(pad "BE32" smd circle
			(at -0.230124 8.820404)
			(size 0.3048 0.3048)
			(layers "F.Cu" "F.Mask" "F.Paste")
			(net "PV_VDDR_NODE1")
		)
		(pad "BE34" smd circle
			(at 0.4699 8.820404)
			(size 0.3048 0.3048)
			(layers "F.Cu" "F.Mask" "F.Paste")
			(net "PV_VDDR_NODE1")
		)
		(pad "BE41" smd circle
			(at 3.742436 8.820404)
			(size 0.3048 0.3048)
			(layers "F.Cu" "F.Mask" "F.Paste")
			(net "PV_VDDR_NODE1")
		)
		(pad "BE42" smd circle
			(at 4.44246 8.820404)
			(size 0.3048 0.3048)
			(layers "F.Cu" "F.Mask" "F.Paste")
			(net "PV_VDDR_NODE1")
		)
		(pad "BE49" smd circle
			(at 7.714996 8.820404)
			(size 0.3048 0.3048)
			(layers "F.Cu" "F.Mask" "F.Paste")
			(net "M_DDR3_NODE1_DQSECCP")
		)
		(pad "BE50" smd circle
			(at 8.41502 8.820404)
			(size 0.3048 0.3048)
			(layers "F.Cu" "F.Mask" "F.Paste")
			(net "GND")
		)
		(pad "BE57" smd circle
			(at 11.687556 8.820404)
			(size 0.3048 0.3048)
			(layers "F.Cu" "F.Mask" "F.Paste")
			(net "M1_DQ_NODE1_DQ47")
		)
		(pad "BE63" smd circle
			(at 14.542516 8.902192)
			(size 0.3048 0.3048)
			(layers "F.Cu" "F.Mask" "F.Paste")
			(net "GND")
		)
		(pad "BE64" smd circle
			(at 15.304516 8.952992)
			(size 0.3048 0.3048)
			(layers "F.Cu" "F.Mask" "F.Paste")
			(net "M1_DQ_NODE1_DQ50")
		)
		(pad "BE66" smd oval
			(at 16.249396 8.902192 90)
			(size 0.254 0.3429)
			(layers "F.Cu" "F.Mask" "F.Paste")
			(net "GND")
		)
		(pad "BF1" smd oval
			(at -16.249396 9.109456 270)
			(size 0.254 0.3429)
			(layers "F.Cu" "F.Mask" "F.Paste")
			(net "TP_CPU_NODE1_RP0_PERN3")
		)
		(pad "BF3" smd circle
			(at -15.304516 9.058656)
			(size 0.3048 0.3048)
			(layers "F.Cu" "F.Mask" "F.Paste")
			(net "TP_CPU_NODE1_RP0_PERP3")
		)
		(pad "BF4" smd circle
			(at -14.542516 9.109456)
			(size 0.3048 0.3048)
			(layers "F.Cu" "F.Mask" "F.Paste")
			(net "CLK_100M_PCIE_RP0_NODE1_DN")
		)
		(pad "BF13" smd circle
			(at -10.161524 9.201404)
			(size 0.3048 0.3048)
			(layers "F.Cu" "F.Mask" "F.Paste")
			(net "M1_DQ_NODE1_DQ7")
		)
		(pad "BF15" smd circle
			(at -9.4615 9.201404)
			(size 0.3048 0.3048)
			(layers "F.Cu" "F.Mask" "F.Paste")
			(net "GND")
		)
		(pad "BF21" smd circle
			(at -6.188964 9.201404)
			(size 0.3048 0.3048)
			(layers "F.Cu" "F.Mask" "F.Paste")
			(net "M1_DQ_NODE1_DQ1")
		)
		(pad "BF23" smd circle
			(at -5.48894 9.201404)
			(size 0.3048 0.3048)
			(layers "F.Cu" "F.Mask" "F.Paste")
			(net "GND")
		)
		(pad "BF29" smd circle
			(at -2.216404 9.201404)
			(size 0.3048 0.3048)
			(layers "F.Cu" "F.Mask" "F.Paste")
			(net "GND")
		)
		(pad "BF30" smd circle
			(at -1.51638 9.201404)
			(size 0.3048 0.3048)
			(layers "F.Cu" "F.Mask" "F.Paste")
			(net "GND")
		)
		(pad "BF37" smd circle
			(at 1.756156 9.201404)
			(size 0.3048 0.3048)
			(layers "F.Cu" "F.Mask" "F.Paste")
			(net "M_DDR3_NODE1_MON2P")
		)
		(pad "BF38" smd circle
			(at 2.45618 9.201404)
			(size 0.3048 0.3048)
			(layers "F.Cu" "F.Mask" "F.Paste")
			(net "M_DDR3_NODE1_MON2N")
		)
		(pad "BF45" smd circle
			(at 5.728716 9.201404)
			(size 0.3048 0.3048)
			(layers "F.Cu" "F.Mask" "F.Paste")
			(net "CLK_100M_DDR3_NODE1_DN")
		)
		(pad "BF46" smd circle
			(at 6.42874 9.201404)
			(size 0.3048 0.3048)
			(layers "F.Cu" "F.Mask" "F.Paste")
			(net "GND")
		)
		(pad "BF53" smd circle
			(at 9.701276 9.201404)
			(size 0.3048 0.3048)
			(layers "F.Cu" "F.Mask" "F.Paste")
			(net "GND")
		)
		(pad "BF54" smd circle
			(at 10.4013 9.201404)
			(size 0.3048 0.3048)
			(layers "F.Cu" "F.Mask" "F.Paste")
			(net "GND")
		)
		(pad "BF62" smd circle
			(at 14.063218 9.412986)
			(size 0.3048 0.3048)
			(layers "F.Cu" "F.Mask" "F.Paste")
			(net "M_DDR3_NODE1_DQS5N")
		)
		(pad "BG1" smd oval
			(at -16.110966 9.859772)
			(size 0.3429 0.2794)
			(layers "F.Cu" "F.Mask" "F.Paste")
			(net "GND")
		)
		(pad "BG4" smd circle
			(at -14.751558 9.78916)
			(size 0.3048 0.3048)
			(layers "F.Cu" "F.Mask" "F.Paste")
			(net "GND")
		)
		(pad "BG5" smd circle
			(at -14.063218 9.62025)
			(size 0.3048 0.3048)
			(layers "F.Cu" "F.Mask" "F.Paste")
			(net "GND")
		)
		(pad "BG8" smd circle
			(at -12.963398 9.701276)
			(size 0.3048 0.3048)
			(layers "F.Cu" "F.Mask" "F.Paste")
			(net "TP_CPU_NODE1_RP0_PETP3")
		)
		(pad "BG9" smd circle
			(at -12.201398 9.701276)
			(size 0.3048 0.3048)
			(layers "F.Cu" "F.Mask" "F.Paste")
			(net "TP_CPU_NODE1_RP0_PETN3")
		)
		(pad "BG11" smd circle
			(at -11.44778 9.582404)
			(size 0.3048 0.3048)
			(layers "F.Cu" "F.Mask" "F.Paste")
			(net "GND")
		)
		(pad "BG13" smd circle
			(at -10.161524 9.963404)
			(size 0.3048 0.3048)
			(layers "F.Cu" "F.Mask" "F.Paste")
			(net "M1_DQ_NODE1_DQ0")
		)
		(pad "BG15" smd circle
			(at -9.4615 9.963404)
			(size 0.3048 0.3048)
			(layers "F.Cu" "F.Mask" "F.Paste")
			(net "M1_DQ_NODE1_DQ2")
		)
		(pad "BG17" smd circle
			(at -8.175244 9.582404)
			(size 0.3048 0.3048)
			(layers "F.Cu" "F.Mask" "F.Paste")
			(net "M_DDR3_NODE1_DQS0P")
		)
		(pad "BG19" smd circle
			(at -7.47522 9.582404)
			(size 0.3048 0.3048)
			(layers "F.Cu" "F.Mask" "F.Paste")
			(net "M1_DQ_NODE1_DQ4")
		)
		(pad "BG21" smd circle
			(at -6.188964 9.963404)
			(size 0.3048 0.3048)
			(layers "F.Cu" "F.Mask" "F.Paste")
			(net "M1_DQ_NODE1_DQ5")
		)
		(pad "BG23" smd circle
			(at -5.48894 9.963404)
			(size 0.3048 0.3048)
			(layers "F.Cu" "F.Mask" "F.Paste")
			(net "GND")
		)
		(pad "BG25" smd circle
			(at -4.202684 9.582404)
			(size 0.3048 0.3048)
			(layers "F.Cu" "F.Mask" "F.Paste")
			(net "M1_DQ_NODE1_DQ18")
		)
		(pad "BG26" smd circle
			(at -3.50266 9.582404)
			(size 0.3048 0.3048)
			(layers "F.Cu" "F.Mask" "F.Paste")
			(net "GND")
		)
		(pad "BG29" smd circle
			(at -2.216404 9.963404)
			(size 0.3048 0.3048)
			(layers "F.Cu" "F.Mask" "F.Paste")
			(net "M1_DQ_NODE1_DQ23")
		)
		(pad "BG30" smd circle
			(at -1.51638 9.963404)
			(size 0.3048 0.3048)
			(layers "F.Cu" "F.Mask" "F.Paste")
			(net "GND")
		)
		(pad "BG32" smd circle
			(at -0.230124 9.582404)
			(size 0.3048 0.3048)
			(layers "F.Cu" "F.Mask" "F.Paste")
			(net "PWRGD_NODE1_DDR3_SYSPWRGD")
		)
		(pad "BG34" smd circle
			(at 0.4699 9.582404)
			(size 0.3048 0.3048)
			(layers "F.Cu" "F.Mask" "F.Paste")
			(net "M_DDR3_NODE1_DQPU")
		)
		(pad "BG37" smd circle
			(at 1.756156 9.963404)
			(size 0.3048 0.3048)
			(layers "F.Cu" "F.Mask" "F.Paste")
			(net "M_DDR3_NODE1_MON1P")
		)
		(pad "BG38" smd circle
			(at 2.45618 9.963404)
			(size 0.3048 0.3048)
			(layers "F.Cu" "F.Mask" "F.Paste")
			(net "M_DDR3_NODE1_MON1N")
		)
		(pad "BG41" smd circle
			(at 3.742436 9.582404)
			(size 0.3048 0.3048)
			(layers "F.Cu" "F.Mask" "F.Paste")
			(net "M_DDR3_NODE1_CK1P")
		)
		(pad "BG42" smd circle
			(at 4.44246 9.582404)
			(size 0.3048 0.3048)
			(layers "F.Cu" "F.Mask" "F.Paste")
			(net "M_DDR3_NODE1_CK1N")
		)
		(pad "BG45" smd circle
			(at 5.728716 9.963404)
			(size 0.3048 0.3048)
			(layers "F.Cu" "F.Mask" "F.Paste")
			(net "CLK_100M_DDR3_NODE1_DP")
		)
		(pad "BG46" smd circle
			(at 6.42874 9.963404)
			(size 0.3048 0.3048)
			(layers "F.Cu" "F.Mask" "F.Paste")
			(net "GND")
		)
		(pad "BG49" smd circle
			(at 7.714996 9.582404)
			(size 0.3048 0.3048)
			(layers "F.Cu" "F.Mask" "F.Paste")
			(net "M_DDR3_NODE1_DQSECCN")
		)
		(pad "BG50" smd circle
			(at 8.41502 9.582404)
			(size 0.3048 0.3048)
			(layers "F.Cu" "F.Mask" "F.Paste")
			(net "M_DDR3_NODE1_ECC0")
		)
		(pad "BG53" smd circle
			(at 9.701276 9.963404)
			(size 0.3048 0.3048)
			(layers "F.Cu" "F.Mask" "F.Paste")
			(net "GND")
		)
		(pad "BG54" smd circle
			(at 10.4013 9.963404)
			(size 0.3048 0.3048)
			(layers "F.Cu" "F.Mask" "F.Paste")
			(net "GND")
		)
		(pad "BG57" smd circle
			(at 11.687556 9.582404)
			(size 0.3048 0.3048)
			(layers "F.Cu" "F.Mask" "F.Paste")
			(net "GND")
		)
		(pad "BG58" smd circle
			(at 12.38758 9.582404)
			(size 0.3048 0.3048)
			(layers "F.Cu" "F.Mask" "F.Paste")
			(net "M1_DQ_NODE1_DQ42")
		)
		(pad "BG63" smd circle
			(at 14.751558 9.581896)
			(size 0.3048 0.3048)
			(layers "F.Cu" "F.Mask" "F.Paste")
			(net "GND")
		)
		(pad "BG66" smd oval
			(at 16.110966 9.859772)
			(size 0.3429 0.2794)
			(layers "F.Cu" "F.Mask" "F.Paste")
			(net "GND")
		)
		(pad "BH3" smd circle
			(at -15.297912 10.317734)
			(size 0.3048 0.3048)
			(layers "F.Cu" "F.Mask" "F.Paste")
			(net "P2E_CPU_NIC1_NODE1_RX_DP")
		)
		(pad "BH5" smd circle
			(at -14.013688 10.32256)
			(size 0.3048 0.3048)
			(layers "F.Cu" "F.Mask" "F.Paste")
			(net "GND")
		)
		(pad "BH8" smd circle
			(at -12.582398 10.344404)
			(size 0.3048 0.3048)
			(layers "F.Cu" "F.Mask" "F.Paste")
			(net "P2E_CPU_NIC1_NODE1_TX_C_DP")
		)
		(pad "BH11" smd circle
			(at -11.44778 10.344404)
			(size 0.3048 0.3048)
			(layers "F.Cu" "F.Mask" "F.Paste")
			(net "GND")
		)
		(pad "BH17" smd circle
			(at -8.175244 10.344404)
			(size 0.3048 0.3048)
			(layers "F.Cu" "F.Mask" "F.Paste")
			(net "M_DDR3_NODE1_DQS0N")
		)
		(pad "BH19" smd circle
			(at -7.47522 10.344404)
			(size 0.3048 0.3048)
			(layers "F.Cu" "F.Mask" "F.Paste")
			(net "M1_DQ_NODE1_DQ3")
		)
		(pad "BH25" smd circle
			(at -4.202684 10.344404)
			(size 0.3048 0.3048)
			(layers "F.Cu" "F.Mask" "F.Paste")
			(net "M1_DQ_NODE1_DQ16")
		)
		(pad "BH26" smd circle
			(at -3.50266 10.344404)
			(size 0.3048 0.3048)
			(layers "F.Cu" "F.Mask" "F.Paste")
			(net "M1_DQ_NODE1_DQ20")
		)
		(pad "BH32" smd circle
			(at -0.230124 10.344404)
			(size 0.3048 0.3048)
			(layers "F.Cu" "F.Mask" "F.Paste")
			(net "M_DDR3_NODE1_ODTPU")
		)
		(pad "BH34" smd circle
			(at 0.4699 10.344404)
			(size 0.3048 0.3048)
			(layers "F.Cu" "F.Mask" "F.Paste")
			(net "M_DDR3_NODE1_CMDPU")
		)
		(pad "BH41" smd circle
			(at 3.742436 10.344404)
			(size 0.3048 0.3048)
			(layers "F.Cu" "F.Mask" "F.Paste")
			(net "N29180194")
		)
		(pad "BH42" smd circle
			(at 4.44246 10.344404)
			(size 0.3048 0.3048)
			(layers "F.Cu" "F.Mask" "F.Paste")
			(net "PWRGD_NODE1_DDR3_DRAM_POK")
		)
		(pad "BH49" smd circle
			(at 7.714996 10.344404)
			(size 0.3048 0.3048)
			(layers "F.Cu" "F.Mask" "F.Paste")
			(net "M_DDR3_NODE1_ECC6")
		)
		(pad "BH50" smd circle
			(at 8.41502 10.344404)
			(size 0.3048 0.3048)
			(layers "F.Cu" "F.Mask" "F.Paste")
			(net "GND")
		)
		(pad "BH57" smd circle
			(at 11.687556 10.344404)
			(size 0.3048 0.3048)
			(layers "F.Cu" "F.Mask" "F.Paste")
			(net "M1_DQ_NODE1_DQ46")
		)
		(pad "BH58" smd circle
			(at 12.38758 10.344404)
			(size 0.3048 0.3048)
			(layers "F.Cu" "F.Mask" "F.Paste")
			(net "M1_DQ_NODE1_DQ40")
		)
		(pad "BH60" smd circle
			(at 13.344398 10.161524)
			(size 0.3048 0.3048)
			(layers "F.Cu" "F.Mask" "F.Paste")
			(net "GND")
		)
		(pad "BH62" smd circle
			(at 14.08049 10.120376)
			(size 0.3048 0.3048)
			(layers "F.Cu" "F.Mask" "F.Paste")
			(net "M_DDR3_NODE1_DQS5P")
		)
		(pad "BH64" smd circle
			(at 15.297912 10.11047)
			(size 0.3048 0.3048)
			(layers "F.Cu" "F.Mask" "F.Paste")
			(net "GND")
		)
		(pad "BJ1" smd circle
			(at -16.110966 10.672572)
			(size 0.4064 0.4064)
			(layers "F.Cu" "F.Mask" "F.Paste")
			(net "GND")
		)
		(pad "BJ4" smd circle
			(at -14.90091 10.903712)
			(size 0.3048 0.3048)
			(layers "F.Cu" "F.Mask" "F.Paste")
			(net "P2E_CPU_NIC1_NODE1_RX_DN")
		)
		(pad "BJ62" smd circle
			(at 14.204442 10.813796)
			(size 0.3048 0.3048)
			(layers "F.Cu" "F.Mask" "F.Paste")
			(net "GND")
		)
		(pad "BJ63" smd circle
			(at 14.90091 10.696448)
			(size 0.3048 0.3048)
			(layers "F.Cu" "F.Mask" "F.Paste")
			(net "GND")
		)
		(pad "BJ66" smd circle
			(at 16.110966 10.672572)
			(size 0.4064 0.4064)
			(layers "F.Cu" "F.Mask" "F.Paste")
			(net "GND")
		)
		(pad "BK1" smd circle
			(at -16.110966 11.485372)
			(size 0.4064 0.4064)
			(layers "F.Cu" "F.Mask" "F.Paste")
			(net "GND")
		)
		(pad "BK3" smd circle
			(at -15.298166 11.485372)
			(size 0.4064 0.4064)
			(layers "F.Cu" "F.Mask" "F.Paste")
			(net "GND")
		)
		(pad "BK5" smd circle
			(at -14.485366 11.485372)
			(size 0.4064 0.4064)
			(layers "F.Cu" "F.Mask" "F.Paste")
			(net "GND")
		)
		(pad "BK6" smd circle
			(at -13.916152 11.063224)
			(size 0.3048 0.3048)
			(layers "F.Cu" "F.Mask" "F.Paste")
			(net "GND")
		)
		(pad "BK8" smd circle
			(at -12.894564 11.063224)
			(size 0.3048 0.3048)
			(layers "F.Cu" "F.Mask" "F.Paste")
			(net "GND")
		)
		(pad "BK9" smd circle
			(at -12.192254 11.013694)
			(size 0.3048 0.3048)
			(layers "F.Cu" "F.Mask" "F.Paste")
			(net "P2E_CPU_NIC1_NODE1_TX_C_DN")
		)
		(pad "BK10" smd circle
			(at -11.514074 11.204448)
			(size 0.3048 0.3048)
			(layers "F.Cu" "F.Mask" "F.Paste")
			(net "GND")
		)
		(pad "BK12" smd circle
			(at -10.81405 11.204448)
			(size 0.3048 0.3048)
			(layers "F.Cu" "F.Mask" "F.Paste")
			(net "GND")
		)
		(pad "BK13" smd circle
			(at -10.12063 11.073638)
			(size 0.3048 0.3048)
			(layers "F.Cu" "F.Mask" "F.Paste")
			(net "GND")
		)
	)
)
